(kicad_pcb
	(version 20260206)
	(generator "pcbnew")
	(generator_version "10.0")
	(general
		(thickness 1.6)
		(legacy_teardrops no)
	)
	(paper "A4")
	(title_block
		(title "04192023_DAF0TMB3IC0_F0TG_MB_C_brd_V02_OCP.brd")
		(comment 1 "Grand Teton / footprints 6947-6952 of 8354")
	)
	(layers
		(0 "F.Cu" signal "TOP")
		(4 "In1.Cu" signal "GND")
		(6 "In2.Cu" signal "IN1")
		(8 "In3.Cu" signal "GND1")
		(10 "In4.Cu" signal "IN2")
		(12 "In5.Cu" signal "GND2")
		(14 "In6.Cu" signal "IN3")
		(16 "In7.Cu" signal "GND3")
		(18 "In8.Cu" signal "VCC")
		(20 "In9.Cu" signal "VCC1")
		(22 "In10.Cu" signal "GND4")
		(24 "In11.Cu" signal "IN4")
		(26 "In12.Cu" signal "GND5")
		(28 "In13.Cu" signal "IN5")
		(30 "In14.Cu" signal "GND6")
		(32 "In15.Cu" signal "IN6")
		(34 "In16.Cu" signal "GND7")
		(2 "B.Cu" signal "BOTTOM")
		(9 "F.Adhes" user "F.Adhesive")
		(11 "B.Adhes" user "B.Adhesive")
		(13 "F.Paste" user "Package Geometry/Pastemask Top")
		(15 "B.Paste" user "Package Geometry/Pastemask Bottom")
		(5 "F.SilkS" user "Ref Des/Silkscreen Top")
		(7 "B.SilkS" user "Ref Des/Silkscreen Bottom")
		(1 "F.Mask" user "Board Geometry/Soldermask Top")
		(3 "B.Mask" user "Board Geometry/Soldermask Bottom")
		(17 "Dwgs.User" user "User.Drawings")
		(19 "Cmts.User" user "User.Comments")
		(21 "Eco1.User" user "User.Eco1")
		(23 "Eco2.User" user "User.Eco2")
		(25 "Edge.Cuts" user "Board Geometry/Outline")
		(27 "Margin" user)
		(31 "F.CrtYd" user "Package Geometry/Place Bound Top")
		(29 "B.CrtYd" user "Package Geometry/Place Bound Bottom")
		(35 "F.Fab" user "Ref Des/Assembly Top")
		(33 "B.Fab" user "Ref Des/Assembly Bottom")
	)
	(footprint ""
		(layer "B.Cu")
		(at 178.303428 -418.4015)
		(property "Reference" "U192"
			(at -0.814578 2.297176 0)
			(unlocked yes)
			(layer "B.SilkS")
			(effects
				(font
					(size 0.7874 0.5842)
					(thickness 0.1524)
				)
				(justify left mirror)
			)
		)
		(property "Value" ""
			(at 0 0 0)
			(layer "B.Fab")
			(effects
				(font
					(size 1.27 1.27)
				)
				(justify mirror)
			)
		)
		(duplicate_pad_numbers_are_jumpers no)
		(fp_line
			(start -1.3716 -1.524)
			(end -1.3716 1.524)
			(stroke
				(width 0.1524)
				(type default)
			)
			(layer "B.SilkS")
		)
		(fp_line
			(start -1.3716 1.524)
			(end 1.3716 1.524)
			(stroke
				(width 0.1524)
				(type default)
			)
			(layer "B.SilkS")
		)
		(fp_line
			(start -0.508 -1.524)
			(end -1.3716 -1.524)
			(stroke
				(width 0.1524)
				(type default)
			)
			(layer "B.SilkS")
		)
		(fp_line
			(start 0 -1.016)
			(end -0.508 -1.524)
			(stroke
				(width 0.1524)
				(type default)
			)
			(layer "B.SilkS")
		)
		(fp_line
			(start 0.508 -1.524)
			(end 0 -1.016)
			(stroke
				(width 0.1524)
				(type default)
			)
			(layer "B.SilkS")
		)
		(fp_line
			(start 1.3716 -1.524)
			(end 0.508 -1.524)
			(stroke
				(width 0.1524)
				(type default)
			)
			(layer "B.SilkS")
		)
		(fp_line
			(start 1.3716 1.524)
			(end 1.3716 -1.524)
			(stroke
				(width 0.1524)
				(type default)
			)
			(layer "B.SilkS")
		)
		(fp_poly
			(pts
				(xy 3.631946 -1.31826) (xy 3.19024 -1.76022) (xy 3.030728 -1.13665)
			)
			(stroke
				(width 0)
				(type default)
			)
			(fill yes)
			(layer "B.SilkS")
		)
		(fp_line
			(start -2.54 -1.0668)
			(end -2.54 1.0668)
			(stroke
				(width 0.1)
				(type default)
			)
			(layer "B.Fab")
		)
		(fp_line
			(start -2.54 1.0668)
			(end -1.5494 1.0668)
			(stroke
				(width 0.1)
				(type default)
			)
			(layer "B.Fab")
		)
		(fp_line
			(start -1.5494 -1.524)
			(end -1.5494 -1.0668)
			(stroke
				(width 0.1)
				(type default)
			)
			(layer "B.Fab")
		)
		(fp_line
			(start -1.5494 -1.0668)
			(end -2.54 -1.0668)
			(stroke
				(width 0.1)
				(type default)
			)
			(layer "B.Fab")
		)
		(fp_line
			(start -1.5494 -1.0668)
			(end -1.5494 1.0668)
			(stroke
				(width 0.1)
				(type default)
			)
			(layer "B.Fab")
		)
		(fp_line
			(start -1.5494 1.0668)
			(end -1.5494 1.524)
			(stroke
				(width 0.1)
				(type default)
			)
			(layer "B.Fab")
		)
		(fp_line
			(start -1.5494 1.524)
			(end 1.5494 1.524)
			(stroke
				(width 0.1)
				(type default)
			)
			(layer "B.Fab")
		)
		(fp_line
			(start 1.5494 -1.524)
			(end -1.5494 -1.524)
			(stroke
				(width 0.1)
				(type default)
			)
			(layer "B.Fab")
		)
		(fp_line
			(start 1.5494 -1.0668)
			(end 1.5494 -1.524)
			(stroke
				(width 0.1)
				(type default)
			)
			(layer "B.Fab")
		)
		(fp_line
			(start 1.5494 1.0668)
			(end 1.5494 -1.0668)
			(stroke
				(width 0.1)
				(type default)
			)
			(layer "B.Fab")
		)
		(fp_line
			(start 1.5494 1.0668)
			(end 2.54 1.0668)
			(stroke
				(width 0.1)
				(type default)
			)
			(layer "B.Fab")
		)
		(fp_line
			(start 1.5494 1.524)
			(end 1.5494 1.0668)
			(stroke
				(width 0.1)
				(type default)
			)
			(layer "B.Fab")
		)
		(fp_line
			(start 2.54 -1.0668)
			(end 1.5494 -1.0668)
			(stroke
				(width 0.1)
				(type default)
			)
			(layer "B.Fab")
		)
		(fp_line
			(start 2.54 1.0668)
			(end 2.54 -1.0668)
			(stroke
				(width 0.1)
				(type default)
			)
			(layer "B.Fab")
		)
		(fp_poly
			(pts
				(xy 3.60172 -0.719328) (xy 3.60172 -1.344168) (xy 3.048 -1.016)
			)
			(stroke
				(width 0)
				(type default)
			)
			(fill yes)
			(layer "B.Fab")
		)
		(pad "1" smd rect
			(at 2.232406 -0.975106 270)
			(size 0.3556 1.4224)
			(layers "B.Cu" "B.Mask" "B.Paste")
			(net "MB_PDB_SMB9_R_EN")
		)
		(pad "2" smd rect
			(at 2.232406 -0.32512 270)
			(size 0.3556 1.4224)
			(layers "B.Cu" "B.Mask" "B.Paste")
			(net "SMB_FAN_3V3AUX_BUF_SCL")
		)
		(pad "3" smd rect
			(at 2.232406 0.32512 270)
			(size 0.3556 1.4224)
			(layers "B.Cu" "B.Mask" "B.Paste")
			(net "SMB_FAN_3V3AUX_R_SCL")
		)
		(pad "4" smd rect
			(at 2.232406 0.975106 270)
			(size 0.3556 1.4224)
			(layers "B.Cu" "B.Mask" "B.Paste")
			(net "GND")
		)
		(pad "5" smd rect
			(at -2.232406 0.975106 270)
			(size 0.3556 1.4224)
			(layers "B.Cu" "B.Mask" "B.Paste")
			(net "Net_10751")
		)
		(pad "6" smd rect
			(at -2.232406 0.32512 270)
			(size 0.3556 1.4224)
			(layers "B.Cu" "B.Mask" "B.Paste")
			(net "SMB_FAN_3V3AUX_R_SDA")
		)
		(pad "7" smd rect
			(at -2.232406 -0.32512 270)
			(size 0.3556 1.4224)
			(layers "B.Cu" "B.Mask" "B.Paste")
			(net "SMB_FAN_3V3AUX_BUF_SDA")
		)
		(pad "8" smd rect
			(at -2.232406 -0.975106 270)
			(size 0.3556 1.4224)
			(layers "B.Cu" "B.Mask" "B.Paste")
			(net "P3V3_AUX")
		)
	)
	(footprint ""
		(layer "B.Cu")
		(at 129.018538 -388.011162 -90)
		(property "Reference" "C473"
			(at 0 0 90)
			(layer "B.SilkS")
			(hide yes)
			(effects
				(font
					(size 1.27 1.27)
				)
				(justify mirror)
			)
		)
		(property "Value" ""
			(at 0 0 90)
			(layer "B.Fab")
			(effects
				(font
					(size 1.27 1.27)
				)
				(justify mirror)
			)
		)
		(duplicate_pad_numbers_are_jumpers no)
		(fp_line
			(start -0.299974 0.150114)
			(end 0.299974 0.150114)
			(stroke
				(width 0.1)
				(type default)
			)
			(layer "B.Fab")
		)
		(fp_line
			(start 0.299974 0.150114)
			(end 0.299974 -0.150114)
			(stroke
				(width 0.1)
				(type default)
			)
			(layer "B.Fab")
		)
		(fp_line
			(start -0.299974 -0.150114)
			(end -0.299974 0.150114)
			(stroke
				(width 0.1)
				(type default)
			)
			(layer "B.Fab")
		)
		(fp_line
			(start 0.299974 -0.150114)
			(end -0.299974 -0.150114)
			(stroke
				(width 0.1)
				(type default)
			)
			(layer "B.Fab")
		)
		(pad "1" smd rect
			(at 0.2667 0 90)
			(size 0.3048 0.381)
			(layers "B.Cu" "B.Mask" "B.Paste")
			(net "P0V9_CPU1_RT3_2A")
		)
		(pad "2" smd rect
			(at -0.2667 0 90)
			(size 0.3048 0.381)
			(layers "B.Cu" "B.Mask" "B.Paste")
			(net "GND")
		)
	)
	(footprint ""
		(layer "B.Cu")
		(at 184.3405 -397.848582)
		(property "Reference" "PR3931"
			(at 0 0 0)
			(layer "B.SilkS")
			(hide yes)
			(effects
				(font
					(size 1.27 1.27)
				)
				(justify mirror)
			)
		)
		(property "Value" ""
			(at 0 0 0)
			(layer "B.Fab")
			(effects
				(font
					(size 1.27 1.27)
				)
				(justify mirror)
			)
		)
		(duplicate_pad_numbers_are_jumpers no)
		(fp_line
			(start -0.7874 -0.4064)
			(end -0.7874 0.4064)
			(stroke
				(width 0.1524)
				(type default)
			)
			(layer "B.SilkS")
		)
		(fp_line
			(start -0.7874 0.4064)
			(end 0.7874 0.4064)
			(stroke
				(width 0.1524)
				(type default)
			)
			(layer "B.SilkS")
		)
		(fp_line
			(start 0.7874 -0.4064)
			(end -0.7874 -0.4064)
			(stroke
				(width 0.1524)
				(type default)
			)
			(layer "B.SilkS")
		)
		(fp_line
			(start 0.7874 0.4064)
			(end 0.7874 -0.4064)
			(stroke
				(width 0.1524)
				(type default)
			)
			(layer "B.SilkS")
		)
		(fp_line
			(start -0.67945 -0.3048)
			(end -0.67945 0.3048)
			(stroke
				(width 0.1)
				(type default)
			)
			(layer "B.Fab")
		)
		(fp_line
			(start -0.67945 0.3048)
			(end -0.120396 0.3048)
			(stroke
				(width 0.1)
				(type default)
			)
			(layer "B.Fab")
		)
		(fp_line
			(start -0.12065 -0.3048)
			(end -0.67945 -0.3048)
			(stroke
				(width 0.1)
				(type default)
			)
			(layer "B.Fab")
		)
		(fp_line
			(start -0.12065 -0.2794)
			(end -0.12065 -0.3048)
			(stroke
				(width 0.1)
				(type default)
			)
			(layer "B.Fab")
		)
		(fp_line
			(start -0.120396 0.2794)
			(end 0.12065 0.2794)
			(stroke
				(width 0.1)
				(type default)
			)
			(layer "B.Fab")
		)
		(fp_line
			(start -0.120396 0.3048)
			(end -0.120396 0.2794)
			(stroke
				(width 0.1)
				(type default)
			)
			(layer "B.Fab")
		)
		(fp_line
			(start 0.12065 -0.305054)
			(end 0.12065 -0.2794)
			(stroke
				(width 0.1)
				(type default)
			)
			(layer "B.Fab")
		)
		(fp_line
			(start 0.12065 -0.2794)
			(end -0.12065 -0.2794)
			(stroke
				(width 0.1)
				(type default)
			)
			(layer "B.Fab")
		)
		(fp_line
			(start 0.12065 0.2794)
			(end 0.12065 0.3048)
			(stroke
				(width 0.1)
				(type default)
			)
			(layer "B.Fab")
		)
		(fp_line
			(start 0.12065 0.3048)
			(end 0.67945 0.3048)
			(stroke
				(width 0.1)
				(type default)
			)
			(layer "B.Fab")
		)
		(fp_line
			(start 0.67945 -0.305054)
			(end 0.12065 -0.305054)
			(stroke
				(width 0.1)
				(type default)
			)
			(layer "B.Fab")
		)
		(fp_line
			(start 0.67945 0.3048)
			(end 0.67945 -0.305054)
			(stroke
				(width 0.1)
				(type default)
			)
			(layer "B.Fab")
		)
		(pad "1" smd circle
			(at 0.40005 0 180)
			(size 0 0)
			(layers "B.Cu" "B.Mask" "B.Paste")
			(net "P12V_AUX")
		)
		(pad "2" smd circle
			(at -0.40005 0 180)
			(size 0 0)
			(layers "B.Cu" "B.Mask" "B.Paste")
			(net "HSC_VOSEN")
		)
	)
	(footprint ""
		(layer "B.Cu")
		(at 75.57008 -4.251198 -90)
		(property "Reference" "R3166"
			(at 0 0 90)
			(layer "B.SilkS")
			(hide yes)
			(effects
				(font
					(size 1.27 1.27)
				)
				(justify mirror)
			)
		)
		(property "Value" ""
			(at 0 0 90)
			(layer "B.Fab")
			(effects
				(font
					(size 1.27 1.27)
				)
				(justify mirror)
			)
		)
		(duplicate_pad_numbers_are_jumpers no)
		(fp_line
			(start -0.7874 0.4064)
			(end 0.7874 0.4064)
			(stroke
				(width 0.1524)
				(type default)
			)
			(layer "B.SilkS")
		)
		(fp_line
			(start 0.7874 0.4064)
			(end 0.7874 -0.4064)
			(stroke
				(width 0.1524)
				(type default)
			)
			(layer "B.SilkS")
		)
		(fp_line
			(start -0.7874 -0.4064)
			(end -0.7874 0.4064)
			(stroke
				(width 0.1524)
				(type default)
			)
			(layer "B.SilkS")
		)
		(fp_line
			(start 0.7874 -0.4064)
			(end -0.7874 -0.4064)
			(stroke
				(width 0.1524)
				(type default)
			)
			(layer "B.SilkS")
		)
		(fp_line
			(start -0.67945 0.3048)
			(end -0.120396 0.3048)
			(stroke
				(width 0.1)
				(type default)
			)
			(layer "B.Fab")
		)
		(fp_line
			(start -0.120396 0.3048)
			(end -0.120396 0.2794)
			(stroke
				(width 0.1)
				(type default)
			)
			(layer "B.Fab")
		)
		(fp_line
			(start 0.12065 0.3048)
			(end 0.67945 0.3048)
			(stroke
				(width 0.1)
				(type default)
			)
			(layer "B.Fab")
		)
		(fp_line
			(start 0.67945 0.3048)
			(end 0.67945 -0.305054)
			(stroke
				(width 0.1)
				(type default)
			)
			(layer "B.Fab")
		)
		(fp_line
			(start -0.120396 0.2794)
			(end 0.12065 0.2794)
			(stroke
				(width 0.1)
				(type default)
			)
			(layer "B.Fab")
		)
		(fp_line
			(start 0.12065 0.2794)
			(end 0.12065 0.3048)
			(stroke
				(width 0.1)
				(type default)
			)
			(layer "B.Fab")
		)
		(fp_line
			(start -0.12065 -0.2794)
			(end -0.12065 -0.3048)
			(stroke
				(width 0.1)
				(type default)
			)
			(layer "B.Fab")
		)
		(fp_line
			(start 0.12065 -0.2794)
			(end -0.12065 -0.2794)
			(stroke
				(width 0.1)
				(type default)
			)
			(layer "B.Fab")
		)
		(fp_line
			(start -0.67945 -0.3048)
			(end -0.67945 0.3048)
			(stroke
				(width 0.1)
				(type default)
			)
			(layer "B.Fab")
		)
		(fp_line
			(start -0.12065 -0.3048)
			(end -0.67945 -0.3048)
			(stroke
				(width 0.1)
				(type default)
			)
			(layer "B.Fab")
		)
		(fp_line
			(start 0.12065 -0.305054)
			(end 0.12065 -0.2794)
			(stroke
				(width 0.1)
				(type default)
			)
			(layer "B.Fab")
		)
		(fp_line
			(start 0.67945 -0.305054)
			(end 0.12065 -0.305054)
			(stroke
				(width 0.1)
				(type default)
			)
			(layer "B.Fab")
		)
		(pad "1" smd circle
			(at 0.40005 0 90)
			(size 0 0)
			(layers "B.Cu" "B.Mask" "B.Paste")
			(net "P3V3_OCP_V3_2")
		)
		(pad "2" smd circle
			(at -0.40005 0 90)
			(size 0 0)
			(layers "B.Cu" "B.Mask" "B.Paste")
			(net "OCP_V3_2_ID1")
		)
	)
	(footprint ""
		(layer "B.Cu")
		(at 115.991386 -250.892564)
		(property "Reference" "C2302"
			(at 0 0 0)
			(layer "B.SilkS")
			(hide yes)
			(effects
				(font
					(size 1.27 1.27)
				)
				(justify mirror)
			)
		)
		(property "Value" ""
			(at 0 0 0)
			(layer "B.Fab")
			(effects
				(font
					(size 1.27 1.27)
				)
				(justify mirror)
			)
		)
		(duplicate_pad_numbers_are_jumpers no)
		(fp_line
			(start -0.7874 -0.4064)
			(end -0.7874 0.4064)
			(stroke
				(width 0.1524)
				(type default)
			)
			(layer "B.SilkS")
		)
		(fp_line
			(start -0.7874 0.4064)
			(end 0.7874 0.4064)
			(stroke
				(width 0.1524)
				(type default)
			)
			(layer "B.SilkS")
		)
		(fp_line
			(start 0.7874 -0.4064)
			(end -0.7874 -0.4064)
			(stroke
				(width 0.1524)
				(type default)
			)
			(layer "B.SilkS")
		)
		(fp_line
			(start 0.7874 0.4064)
			(end 0.7874 -0.4064)
			(stroke
				(width 0.1524)
				(type default)
			)
			(layer "B.SilkS")
		)
		(fp_line
			(start -0.67945 -0.3048)
			(end -0.67945 0.3048)
			(stroke
				(width 0.1)
				(type default)
			)
			(layer "B.Fab")
		)
		(fp_line
			(start -0.67945 0.3048)
			(end -0.120396 0.3048)
			(stroke
				(width 0.1)
				(type default)
			)
			(layer "B.Fab")
		)
		(fp_line
			(start -0.12065 -0.3048)
			(end -0.67945 -0.3048)
			(stroke
				(width 0.1)
				(type default)
			)
			(layer "B.Fab")
		)
		(fp_line
			(start -0.12065 -0.2794)
			(end -0.12065 -0.3048)
			(stroke
				(width 0.1)
				(type default)
			)
			(layer "B.Fab")
		)
		(fp_line
			(start -0.120396 0.2794)
			(end 0.12065 0.2794)
			(stroke
				(width 0.1)
				(type default)
			)
			(layer "B.Fab")
		)
		(fp_line
			(start -0.120396 0.3048)
			(end -0.120396 0.2794)
			(stroke
				(width 0.1)
				(type default)
			)
			(layer "B.Fab")
		)
		(fp_line
			(start 0.12065 -0.305054)
			(end 0.12065 -0.2794)
			(stroke
				(width 0.1)
				(type default)
			)
			(layer "B.Fab")
		)
		(fp_line
			(start 0.12065 -0.2794)
			(end -0.12065 -0.2794)
			(stroke
				(width 0.1)
				(type default)
			)
			(layer "B.Fab")
		)
		(fp_line
			(start 0.12065 0.2794)
			(end 0.12065 0.3048)
			(stroke
				(width 0.1)
				(type default)
			)
			(layer "B.Fab")
		)
		(fp_line
			(start 0.12065 0.3048)
			(end 0.67945 0.3048)
			(stroke
				(width 0.1)
				(type default)
			)
			(layer "B.Fab")
		)
		(fp_line
			(start 0.67945 -0.305054)
			(end 0.12065 -0.305054)
			(stroke
				(width 0.1)
				(type default)
			)
			(layer "B.Fab")
		)
		(fp_line
			(start 0.67945 0.3048)
			(end 0.67945 -0.305054)
			(stroke
				(width 0.1)
				(type default)
			)
			(layer "B.Fab")
		)
		(pad "1" smd circle
			(at 0.40005 0 180)
			(size 0 0)
			(layers "B.Cu" "B.Mask" "B.Paste")
			(net "PVDDCR_CPU0_P1")
		)
		(pad "2" smd circle
			(at -0.40005 0 180)
			(size 0 0)
			(layers "B.Cu" "B.Mask" "B.Paste")
			(net "GND")
		)
	)
	(footprint ""
		(layer "B.Cu")
		(at 310.7182 -396.393162 -90)
		(property "Reference" "C512"
			(at 0 0 90)
			(layer "B.SilkS")
			(hide yes)
			(effects
				(font
					(size 1.27 1.27)
				)
				(justify mirror)
			)
		)
		(property "Value" ""
			(at 0 0 90)
			(layer "B.Fab")
			(effects
				(font
					(size 1.27 1.27)
				)
				(justify mirror)
			)
		)
		(duplicate_pad_numbers_are_jumpers no)
		(fp_line
			(start -0.299974 0.150114)
			(end 0.299974 0.150114)
			(stroke
				(width 0.1)
				(type default)
			)
			(layer "B.Fab")
		)
		(fp_line
			(start 0.299974 0.150114)
			(end 0.299974 -0.150114)
			(stroke
				(width 0.1)
				(type default)
			)
			(layer "B.Fab")
		)
		(fp_line
			(start -0.299974 -0.150114)
			(end -0.299974 0.150114)
			(stroke
				(width 0.1)
				(type default)
			)
			(layer "B.Fab")
		)
		(fp_line
			(start 0.299974 -0.150114)
			(end -0.299974 -0.150114)
			(stroke
				(width 0.1)
				(type default)
			)
			(layer "B.Fab")
		)
		(pad "1" smd rect
			(at 0.2667 0 90)
			(size 0.3048 0.381)
			(layers "B.Cu" "B.Mask" "B.Paste")
			(net "P1V8_CPU0_RT0_1A")
		)
		(pad "2" smd rect
			(at -0.2667 0 90)
			(size 0.3048 0.381)
			(layers "B.Cu" "B.Mask" "B.Paste")
			(net "GND")
		)
	)
)
